# BASEBOARD_FAB2 (Tioga Pass) — schematic netlist excerpt (pin names and nets, part order shuffled) for the footprints in the layout excerpt that follows; sources: Cadence DE-HDL packaged netlist, KiCad conversion of Wiwynn_Tioga_Pass_MB.brd

C8P27  CAP  47UF 4V 20% X6S  pkg 0805  page 76 : A = PVCCIN_CPU1 ; B = GND
R9P20  RES  2.7K 1% CHIP  pkg 0402  page 200 : A = P3V3_STBY ; B = FM_HSC_TIMER_EXP_N
C2T28  CAP_A  1.0UF 6.3V 10% X6S  pkg 0402V  page 101 : A = P3V3_STBY ; B = GND

(kicad_pcb
	(version 20260206)
	(generator "pcbnew")
	(generator_version "10.0")
	(general
		(thickness 1.6)
		(legacy_teardrops no)
	)
	(paper "A4")
	(title_block
		(title "Wiwynn_Tioga_Pass_MB.brd")
		(comment 1 "Tioga Pass / footprints 2399-2401 of 4770")
	)
	(layers
		(0 "F.Cu" signal "TOP")
		(4 "In1.Cu" signal "L2GND")
		(6 "In2.Cu" signal "L3")
		(8 "In3.Cu" signal "L4GND")
		(10 "In4.Cu" signal "L5")
		(12 "In5.Cu" signal "L6GND")
		(14 "In6.Cu" signal "L7VCC")
		(16 "In7.Cu" signal "L8VCC")
		(18 "In8.Cu" signal "L9GND")
		(20 "In9.Cu" signal "L10")
		(22 "In10.Cu" signal "L11GND")
		(24 "In11.Cu" signal "L12")
		(26 "In12.Cu" signal "L13GND")
		(2 "B.Cu" signal "BOTTOM")
		(9 "F.Adhes" user "F.Adhesive")
		(11 "B.Adhes" user "B.Adhesive")
		(13 "F.Paste" user "Package Geometry/Pastemask Top")
		(15 "B.Paste" user "Package Geometry/Pastemask Bottom")
		(5 "F.SilkS" user "Ref Des/Silkscreen Top")
		(7 "B.SilkS" user "Ref Des/Silkscreen Bottom")
		(1 "F.Mask" user "Board Geometry/Soldermask Top")
		(3 "B.Mask" user "Board Geometry/Soldermask Bottom")
		(17 "Dwgs.User" user "User.Drawings")
		(19 "Cmts.User" user "User.Comments")
		(21 "Eco1.User" user "User.Eco1")
		(23 "Eco2.User" user "User.Eco2")
		(25 "Edge.Cuts" user "Board Geometry/Outline")
		(27 "Margin" user)
		(31 "F.CrtYd" user "Package Geometry/Place Bound Top")
		(29 "B.CrtYd" user "Package Geometry/Place Bound Bottom")
		(35 "F.Fab" user "Ref Des/Assembly Top")
		(33 "B.Fab" user "Ref Des/Assembly Bottom")
	)
	(footprint ""
		(layer "B.Cu")
		(at 97.206054 -73.51014)
		(property "Reference" "C8P27"
			(at 0 0 0)
			(layer "B.SilkS")
			(hide yes)
			(effects
				(font
					(size 1.27 1.27)
				)
				(justify mirror)
			)
		)
		(property "Value" ""
			(at 0 0 0)
			(layer "B.Fab")
			(effects
				(font
					(size 1.27 1.27)
				)
				(justify mirror)
			)
		)
		(duplicate_pad_numbers_are_jumpers no)
		(fp_poly
			(pts
				(xy 0.7239 -0.2159) (xy -0.7239 -0.2159) (xy -0.7239 1.9939) (xy 0.7239 1.9939)
			)
			(stroke
				(width 0)
				(type default)
			)
			(fill no)
			(layer "B.CrtYd")
		)
		(fp_line
			(start -0.7239 -0.2159)
			(end 0.7239 -0.2159)
			(stroke
				(width 0.1)
				(type default)
			)
			(layer "B.Fab")
		)
		(fp_line
			(start -0.7239 1.9939)
			(end -0.7239 -0.2159)
			(stroke
				(width 0.1)
				(type default)
			)
			(layer "B.Fab")
		)
		(fp_line
			(start 0.7239 -0.2159)
			(end 0.7239 1.9939)
			(stroke
				(width 0.1)
				(type default)
			)
			(layer "B.Fab")
		)
		(fp_line
			(start 0.7239 1.9939)
			(end -0.7239 1.9939)
			(stroke
				(width 0.1)
				(type default)
			)
			(layer "B.Fab")
		)
		(pad "1" smd rect
			(at 0 0 180)
			(size 1.27 1.016)
			(layers "B.Cu" "B.Mask" "B.Paste")
			(net "PVCCIN_CPU1")
		)
		(pad "2" smd rect
			(at 0 1.778 180)
			(size 1.27 1.016)
			(layers "B.Cu" "B.Mask" "B.Paste")
			(net "GND")
		)
		(zone
			(layer "B.Cu")
			(hatch none 0.5)
			(connect_pads
				(clearance 0)
			)
			(min_thickness 0.25)
			(keepout
				(tracks not_allowed)
				(vias allowed)
				(pads allowed)
				(copperpour not_allowed)
				(footprints allowed)
			)
			(placement
				(enabled no)
				(sheetname "")
			)
			(fill
				(thermal_gap 0.5)
				(thermal_bridge_width 0.5)
				(island_removal_mode 0)
			)
			(polygon
				(pts
					(xy 97.841054 -73.00214) (xy 96.571054 -73.00214) (xy 96.571054 -72.24014) (xy 97.841054 -72.24014)
				)
			)
		)
	)
	(footprint ""
		(layer "B.Cu")
		(at 482.854 -32.512 180)
		(property "Reference" "C2T28"
			(at 0 0 0)
			(layer "B.SilkS")
			(hide yes)
			(effects
				(font
					(size 1.27 1.27)
				)
				(justify mirror)
			)
		)
		(property "Value" ""
			(at 0 0 0)
			(layer "B.Fab")
			(effects
				(font
					(size 1.27 1.27)
				)
				(justify mirror)
			)
		)
		(duplicate_pad_numbers_are_jumpers no)
		(fp_poly
			(pts
				(xy -0.3048 -0.1016) (xy -0.3048 0.9906) (xy 0.3048 0.9906) (xy 0.3048 -0.1016)
			)
			(stroke
				(width 0)
				(type default)
			)
			(fill no)
			(layer "B.CrtYd")
		)
		(fp_line
			(start 0.3048 0.9906)
			(end -0.3048 0.9906)
			(stroke
				(width 0.1)
				(type default)
			)
			(layer "B.Fab")
		)
		(fp_line
			(start 0.3048 -0.1016)
			(end 0.3048 0.9906)
			(stroke
				(width 0.1)
				(type default)
			)
			(layer "B.Fab")
		)
		(fp_line
			(start -0.3048 0.9906)
			(end -0.3048 -0.1016)
			(stroke
				(width 0.1)
				(type default)
			)
			(layer "B.Fab")
		)
		(fp_line
			(start -0.3048 -0.1016)
			(end 0.3048 -0.1016)
			(stroke
				(width 0.1)
				(type default)
			)
			(layer "B.Fab")
		)
		(pad "1" smd rect
			(at 0 0)
			(size 0.508 0.508)
			(layers "B.Cu" "B.Mask" "B.Paste")
			(net "P3V3_STBY")
		)
		(pad "2" smd rect
			(at 0 0.889)
			(size 0.508 0.508)
			(layers "B.Cu" "B.Mask" "B.Paste")
			(net "GND")
		)
		(zone
			(layer "B.Cu")
			(hatch none 0.5)
			(connect_pads
				(clearance 0)
			)
			(min_thickness 0.25)
			(keepout
				(tracks not_allowed)
				(vias allowed)
				(pads allowed)
				(copperpour not_allowed)
				(footprints allowed)
			)
			(placement
				(enabled no)
				(sheetname "")
			)
			(fill
				(thermal_gap 0.5)
				(thermal_bridge_width 0.5)
				(island_removal_mode 0)
			)
			(polygon
				(pts
					(xy 482.6 -33.147) (xy 483.108 -33.147) (xy 483.108 -32.766) (xy 482.6 -32.766)
				)
			)
		)
		(zone
			(layer "B.Cu")
			(hatch none 0.5)
			(connect_pads
				(clearance 0)
			)
			(min_thickness 0.25)
			(keepout
				(tracks allowed)
				(vias not_allowed)
				(pads allowed)
				(copperpour not_allowed)
				(footprints allowed)
			)
			(placement
				(enabled no)
				(sheetname "")
			)
			(fill
				(thermal_gap 0.5)
				(thermal_bridge_width 0.5)
				(island_removal_mode 0)
			)
			(polygon
				(pts
					(xy 482.6 -32.766) (xy 483.108 -32.766) (xy 483.108 -33.147) (xy 482.6 -33.147)
				)
			)
		)
	)
	(footprint ""
		(layer "B.Cu")
		(at 27.0764 -77.089 180)
		(property "Reference" "R9P20"
			(at 0 0 0)
			(layer "B.SilkS")
			(hide yes)
			(effects
				(font
					(size 1.27 1.27)
				)
				(justify mirror)
			)
		)
		(property "Value" ""
			(at 0 0 0)
			(layer "B.Fab")
			(effects
				(font
					(size 1.27 1.27)
				)
				(justify mirror)
			)
		)
		(duplicate_pad_numbers_are_jumpers no)
		(fp_poly
			(pts
				(xy 0.2794 -0.1016) (xy -0.2794 -0.1016) (xy -0.2794 0.9906) (xy 0.2794 0.9906)
			)
			(stroke
				(width 0)
				(type default)
			)
			(fill no)
			(layer "B.CrtYd")
		)
		(fp_line
			(start 0.2794 0.9906)
			(end -0.2794 0.9906)
			(stroke
				(width 0.1)
				(type default)
			)
			(layer "B.Fab")
		)
		(fp_line
			(start 0.2794 -0.1016)
			(end 0.2794 0.9906)
			(stroke
				(width 0.1)
				(type default)
			)
			(layer "B.Fab")
		)
		(fp_line
			(start -0.2794 0.9906)
			(end -0.2794 -0.1016)
			(stroke
				(width 0.1)
				(type default)
			)
			(layer "B.Fab")
		)
		(fp_line
			(start -0.2794 -0.1016)
			(end 0.2794 -0.1016)
			(stroke
				(width 0.1)
				(type default)
			)
			(layer "B.Fab")
		)
		(pad "1" smd rect
			(at 0 0)
			(size 0.508 0.508)
			(layers "B.Cu" "B.Mask" "B.Paste")
			(net "P3V3_STBY")
		)
		(pad "2" smd rect
			(at 0 0.889)
			(size 0.508 0.508)
			(layers "B.Cu" "B.Mask" "B.Paste")
			(net "FM_HSC_TIMER_EXP_N")
		)
		(zone
			(layer "B.Cu")
			(hatch none 0.5)
			(connect_pads
				(clearance 0)
			)
			(min_thickness 0.25)
			(keepout
				(tracks not_allowed)
				(vias allowed)
				(pads allowed)
				(copperpour not_allowed)
				(footprints allowed)
			)
			(placement
				(enabled no)
				(sheetname "")
			)
			(fill
				(thermal_gap 0.5)
				(thermal_bridge_width 0.5)
				(island_removal_mode 0)
			)
			(polygon
				(pts
					(xy 26.8224 -77.724) (xy 27.3304 -77.724) (xy 27.3304 -77.343) (xy 26.8224 -77.343)
				)
			)
		)
		(zone
			(layer "B.Cu")
			(hatch none 0.5)
			(connect_pads
				(clearance 0)
			)
			(min_thickness 0.25)
			(keepout
				(tracks allowed)
				(vias not_allowed)
				(pads allowed)
				(copperpour not_allowed)
				(footprints allowed)
			)
			(placement
				(enabled no)
				(sheetname "")
			)
			(fill
				(thermal_gap 0.5)
				(thermal_bridge_width 0.5)
				(island_removal_mode 0)
			)
			(polygon
				(pts
					(xy 26.8224 -77.343) (xy 27.3304 -77.343) (xy 27.3304 -77.724) (xy 26.8224 -77.724)
				)
			)
		)
	)
)
